(kicad_pcb
	(version 20241229)
	(generator "pcbnew")
	(generator_version "9.0")
	(general
		(thickness 1.61)
		(legacy_teardrops no)
	)
	(paper "A3")
	(title_block
		(title "RDIMM DDR5 Tester")
		(date "2026-05-21")
		(rev "2.2.0")
		(company "Antmicro")
		(comment 9 "footprints 319-321 of 796")
	)
	(layers
		(0 "F.Cu" signal)
		(4 "In1.Cu" power)
		(6 "In2.Cu" mixed)
		(8 "In3.Cu" power)
		(10 "In4.Cu" mixed)
		(12 "In5.Cu" power)
		(14 "In6.Cu" mixed)
		(16 "In7.Cu" power)
		(18 "In8.Cu" power)
		(20 "In9.Cu" mixed)
		(22 "In10.Cu" power)
		(2 "B.Cu" signal)
		(9 "F.Adhes" user "F.Adhesive")
		(11 "B.Adhes" user "B.Adhesive")
		(13 "F.Paste" user)
		(15 "B.Paste" user)
		(5 "F.SilkS" user "F.Silkscreen")
		(7 "B.SilkS" user "B.Silkscreen")
		(1 "F.Mask" user)
		(3 "B.Mask" user)
		(17 "Dwgs.User" user "User.Drawings")
		(19 "Cmts.User" user "User.Comments")
		(21 "Eco1.User" user "User.Eco1")
		(23 "Eco2.User" user "User.Eco2")
		(25 "Edge.Cuts" user)
		(27 "Margin" user)
		(31 "F.CrtYd" user "F.Courtyard")
		(29 "B.CrtYd" user "B.Courtyard")
		(35 "F.Fab" user)
		(33 "B.Fab" user)
	)
	(footprint "antmicro-footprints:VQFN-16-1EP_3x3mm_P0.5mm_EP1.1x1.1mm"
		(layer "F.Cu")
		(at 239.274499 155.3085 180)
		(descr "VQFN, 16 Pin (https://ww1.microchip.com/downloads/en/DeviceDoc/16L_VQFN-WFS_3x3mm_4MX_C04-00508a.pdf), generated with kicad-footprint-generator ipc_noLead_generator.py")
		(tags "VQFN NoLead")
		(property "Reference" "U28"
			(at -1.175501 -3.6165 0)
			(layer "F.SilkS")
			(effects
				(font
					(size 0.7 0.7)
					(thickness 0.15)
				)
				(justify right bottom)
			)
		)
		(property "Value" "PAC1944T-E"
			(at 0 2.797 0)
			(layer "F.Fab")
			(effects
				(font
					(size 0.7 0.7)
					(thickness 0.15)
				)
				(justify right bottom)
			)
		)
		(property "Datasheet" "https://ww1.microchip.com/downloads/aemDocuments/documents/MSLD/ProductDocuments/DataSheets/PAC194X-Family-Data-Sheet-DS20006543.pdf"
			(at 0 0 180)
			(layer "F.Fab")
			(hide yes)
			(effects
				(font
					(size 1.27 1.27)
					(thickness 0.15)
				)
			)
		)
		(property "MPN" "PAC1944T-E/4MX"
			(at 0 0 180)
			(unlocked yes)
			(layer "F.Fab")
			(hide yes)
			(effects
				(font
					(size 1 1)
					(thickness 0.15)
				)
			)
		)
		(property "Manufacturer" "Microchip Technology"
			(at 0 0 180)
			(unlocked yes)
			(layer "F.Fab")
			(hide yes)
			(effects
				(font
					(size 1 1)
					(thickness 0.15)
				)
			)
		)
		(property "Author" "Antmicro"
			(at 0 0 180)
			(unlocked yes)
			(layer "F.Fab")
			(hide yes)
			(effects
				(font
					(size 1 1)
					(thickness 0.15)
				)
			)
		)
		(property "License" "Apache-2.0"
			(at 0 0 180)
			(unlocked yes)
			(layer "F.Fab")
			(hide yes)
			(effects
				(font
					(size 1 1)
					(thickness 0.15)
				)
			)
		)
		(property ki_fp_filters "UQFN*1EP*4x4mm*P0.65mm*")
		(sheetname "/Supply/DC-DC IO/")
		(sheetfile "dc-dc-io.kicad_sch")
		(attr smd)
		(fp_line
			(start 1.61 1.61)
			(end 1.61 1.134)
			(stroke
				(width 0.15)
				(type solid)
			)
			(layer "F.SilkS")
		)
		(fp_line
			(start 1.61 -1.611)
			(end 1.61 -1.135)
			(stroke
				(width 0.15)
				(type solid)
			)
			(layer "F.SilkS")
		)
		(fp_line
			(start 1.134 1.61)
			(end 1.61 1.61)
			(stroke
				(width 0.15)
				(type solid)
			)
			(layer "F.SilkS")
		)
		(fp_line
			(start 1.134 -1.611)
			(end 1.61 -1.611)
			(stroke
				(width 0.15)
				(type solid)
			)
			(layer "F.SilkS")
		)
		(fp_line
			(start -1.135 1.61)
			(end -1.611 1.61)
			(stroke
				(width 0.15)
				(type solid)
			)
			(layer "F.SilkS")
		)
		(fp_line
			(start -1.135 -1.611)
			(end -1.611 -1.611)
			(stroke
				(width 0.15)
				(type solid)
			)
			(layer "F.SilkS")
		)
		(fp_line
			(start -1.611 1.61)
			(end -1.611 1.134)
			(stroke
				(width 0.15)
				(type solid)
			)
			(layer "F.SilkS")
		)
		(fp_circle
			(center -2.3 -0.75)
			(end -2.25 -0.75)
			(stroke
				(width 0.15)
				(type solid)
			)
			(fill yes)
			(layer "F.SilkS")
		)
		(fp_rect
			(start -2 -2)
			(end 1.999 1.999)
			(stroke
				(width 0.05)
				(type solid)
			)
			(fill no)
			(layer "F.CrtYd")
		)
		(fp_line
			(start 1.499 1.499)
			(end -1.5 1.499)
			(stroke
				(width 0.15)
				(type solid)
			)
			(layer "F.Fab")
		)
		(fp_line
			(start 1.499 -1.5)
			(end 1.499 1.499)
			(stroke
				(width 0.15)
				(type solid)
			)
			(layer "F.Fab")
		)
		(fp_line
			(start -0.75 -1.5)
			(end 1.499 -1.5)
			(stroke
				(width 0.15)
				(type solid)
			)
			(layer "F.Fab")
		)
		(fp_line
			(start -1.5 1.499)
			(end -1.5 -0.75)
			(stroke
				(width 0.15)
				(type solid)
			)
			(layer "F.Fab")
		)
		(fp_line
			(start -1.5 -0.75)
			(end -0.75 -1.5)
			(stroke
				(width 0.15)
				(type solid)
			)
			(layer "F.Fab")
		)
		(fp_circle
			(center -2.3 -0.75)
			(end -2.25 -0.75)
			(stroke
				(width 0.15)
				(type solid)
			)
			(fill yes)
			(layer "F.Fab")
		)
		(fp_text user "License: Apache-2.0"
			(at -2.35 7.197 180)
			(layer "F.Fab")
			(effects
				(font
					(size 0.7 0.7)
					(thickness 0.15)
				)
				(justify left bottom)
			)
		)
		(fp_text user "${REFERENCE}"
			(at -2.35 4.797 180)
			(layer "F.Fab")
			(effects
				(font
					(size 0.7 0.7)
					(thickness 0.15)
				)
				(justify left bottom)
			)
		)
		(fp_text user "Author: Antmicro"
			(at -2.35 5.997 180)
			(layer "F.Fab")
			(effects
				(font
					(size 0.7 0.7)
					(thickness 0.15)
				)
				(justify left bottom)
			)
		)
		(pad "" smd roundrect
			(at 0 0 180)
			(size 0.89 0.89)
			(layers "F.Paste")
			(roundrect_rratio 0.25)
		)
		(pad "1" smd roundrect
			(at -1.464 -0.75 180)
			(size 0.775 0.25)
			(layers "F.Cu" "F.Mask" "F.Paste")
			(roundrect_rratio 0.25)
			(net 744 "unconnected-(U28-SLOW{slash}~{ALERT1}-Pad1)")
			(pinfunction "SLOW/~{ALERT1}")
			(pintype "bidirectional+no_connect")
		)
		(pad "2" smd roundrect
			(at -1.464 -0.25 180)
			(size 0.775 0.25)
			(layers "F.Cu" "F.Mask" "F.Paste")
			(roundrect_rratio 0.25)
			(net 38 "+3V3_AON")
			(pinfunction "VDD")
			(pintype "power_in")
		)
		(pad "3" smd roundrect
			(at -1.464 0.247 180)
			(size 0.775 0.25)
			(layers "F.Cu" "F.Mask" "F.Paste")
			(roundrect_rratio 0.25)
			(net 1 "GND")
			(pinfunction "GND")
			(pintype "power_in")
		)
		(pad "4" smd roundrect
			(at -1.464 0.747 180)
			(size 0.775 0.25)
			(layers "F.Cu" "F.Mask" "F.Paste")
			(roundrect_rratio 0.25)
			(net 749 "/I^{2}C + I3C/PWR.SCL")
			(pinfunction "SCL")
			(pintype "input")
		)
		(pad "5" smd roundrect
			(at -0.75 1.461 180)
			(size 0.25 0.775)
			(layers "F.Cu" "F.Mask" "F.Paste")
			(roundrect_rratio 0.25)
			(net 533 "/I^{2}C + I3C/PWR.SDA")
			(pinfunction "SDA")
			(pintype "bidirectional")
		)
		(pad "6" smd roundrect
			(at -0.25 1.461 180)
			(size 0.25 0.775)
			(layers "F.Cu" "F.Mask" "F.Paste")
			(roundrect_rratio 0.25)
			(net 1 "GND")
			(pinfunction "ADDRSEL")
			(pintype "bidirectional")
		)
		(pad "7" smd roundrect
			(at 0.247 1.461 180)
			(size 0.25 0.775)
			(layers "F.Cu" "F.Mask" "F.Paste")
			(roundrect_rratio 0.25)
			(net 819 "/Supply/DC-DC IO/VDDQ_SEN_-")
			(pinfunction "IN3-")
			(pintype "input")
		)
		(pad "8" smd roundrect
			(at 0.747 1.461 180)
			(size 0.25 0.775)
			(layers "F.Cu" "F.Mask" "F.Paste")
			(roundrect_rratio 0.25)
			(net 733 "Net-(U28-IN3+)")
			(pinfunction "IN3+")
			(pintype "input")
		)
		(pad "9" smd roundrect
			(at 1.461 0.747 180)
			(size 0.775 0.25)
			(layers "F.Cu" "F.Mask" "F.Paste")
			(roundrect_rratio 0.25)
			(net 696 "/Supply/DC-DC IO/1V2_SEN_-")
			(pinfunction "IN4-")
			(pintype "input")
		)
		(pad "10" smd roundrect
			(at 1.461 0.247 180)
			(size 0.775 0.25)
			(layers "F.Cu" "F.Mask" "F.Paste")
			(roundrect_rratio 0.25)
			(net 734 "Net-(U28-IN4+)")
			(pinfunction "IN4+")
			(pintype "input")
		)
		(pad "11" smd roundrect
			(at 1.461 -0.25 180)
			(size 0.775 0.25)
			(layers "F.Cu" "F.Mask" "F.Paste")
			(roundrect_rratio 0.25)
			(net 730 "Net-(U28-IN1+)")
			(pinfunction "IN1+")
			(pintype "input")
		)
		(pad "12" smd roundrect
			(at 1.461 -0.75 180)
			(size 0.775 0.25)
			(layers "F.Cu" "F.Mask" "F.Paste")
			(roundrect_rratio 0.25)
			(net 693 "/Supply/DC-DC IO/3V3_SEN_-")
			(pinfunction "IN1-")
			(pintype "input")
		)
		(pad "13" smd roundrect
			(at 0.747 -1.464 180)
			(size 0.25 0.775)
			(layers "F.Cu" "F.Mask" "F.Paste")
			(roundrect_rratio 0.25)
			(net 732 "Net-(U28-IN2+)")
			(pinfunction "IN2+")
			(pintype "input")
		)
		(pad "14" smd roundrect
			(at 0.247 -1.464 180)
			(size 0.25 0.775)
			(layers "F.Cu" "F.Mask" "F.Paste")
			(roundrect_rratio 0.25)
			(net 694 "/Supply/DC-DC IO/5V_SEN_-")
			(pinfunction "IN2-")
			(pintype "input")
		)
		(pad "15" smd roundrect
			(at -0.25 -1.464 180)
			(size 0.25 0.775)
			(layers "F.Cu" "F.Mask" "F.Paste")
			(roundrect_rratio 0.25)
			(net 745 "unconnected-(U28-GPIO{slash}~{ALERT2}-Pad15)")
			(pinfunction "GPIO/~{ALERT2}")
			(pintype "bidirectional+no_connect")
		)
		(pad "16" smd roundrect
			(at -0.75 -1.464 180)
			(size 0.25 0.775)
			(layers "F.Cu" "F.Mask" "F.Paste")
			(roundrect_rratio 0.25)
			(net 720 "Net-(U28-~{PWRDN})")
			(pinfunction "~{PWRDN}")
			(pintype "input")
		)
		(pad "17" smd rect
			(at 0 0 180)
			(size 1.1 1.1)
			(layers "F.Cu" "F.Mask")
			(net 1 "GND")
			(pinfunction "EP")
			(pintype "passive")
		)
	)
	(footprint "antmicro-footprints:R_0402_1005Metric"
		(layer "F.Cu")
		(at 243.051 117.5)
		(descr "Resistor SMD 0402")
		(tags "resistor SMD 0402")
		(property "Reference" "R242"
			(at -3.95 0.1 0)
			(layer "F.SilkS")
			(effects
				(font
					(size 0.7 0.7)
					(thickness 0.15)
				)
				(justify left bottom)
			)
		)
		(property "Value" "R_4k7_0402"
			(at -1.011843 1.772047 0)
			(layer "F.Fab")
			(effects
				(font
					(size 0.7 0.7)
					(thickness 0.15)
				)
				(justify left bottom)
			)
		)
		(property "Datasheet" "https://www.bourns.com/docs/product-datasheets/cr.pdf"
			(at 0 0 0)
			(layer "B.Fab")
			(hide yes)
			(effects
				(font
					(size 1.27 1.27)
					(thickness 0.15)
				)
				(justify mirror)
			)
		)
		(property "MPN" "CR0402-FX-4701GLF"
			(at 0 0 0)
			(unlocked yes)
			(layer "F.Fab")
			(hide yes)
			(effects
				(font
					(size 1 1)
					(thickness 0.15)
				)
			)
		)
		(property "Manufacturer" "Bourns"
			(at 0 0 0)
			(unlocked yes)
			(layer "F.Fab")
			(hide yes)
			(effects
				(font
					(size 1 1)
					(thickness 0.15)
				)
			)
		)
		(property "License" "Apache-2.0"
			(at 0 0 0)
			(unlocked yes)
			(layer "F.Fab")
			(hide yes)
			(effects
				(font
					(size 1 1)
					(thickness 0.15)
				)
			)
		)
		(property "Author" "Antmicro"
			(at 0 0 0)
			(unlocked yes)
			(layer "F.Fab")
			(hide yes)
			(effects
				(font
					(size 1 1)
					(thickness 0.15)
				)
			)
		)
		(property "Val" "4k7"
			(at 0 0 0)
			(unlocked yes)
			(layer "F.Fab")
			(hide yes)
			(effects
				(font
					(size 1 1)
					(thickness 0.15)
				)
			)
		)
		(property "Tolerance" "1%"
			(at 0 0 0)
			(unlocked yes)
			(layer "F.Fab")
			(hide yes)
			(effects
				(font
					(size 1 1)
					(thickness 0.15)
				)
			)
		)
		(sheetname "/DDR5 RDIMM/")
		(sheetfile "ddr5-rdimm.kicad_sch")
		(attr smd)
		(fp_rect
			(start -0.925 -0.47)
			(end 0.925 0.47)
			(stroke
				(width 0.05)
				(type default)
			)
			(fill no)
			(layer "F.CrtYd")
		)
		(fp_rect
			(start -0.5 -0.25)
			(end 0.5 0.25)
			(stroke
				(width 0.15)
				(type solid)
			)
			(fill no)
			(layer "F.Fab")
		)
		(fp_text user "Author: Antmicro"
			(at -0.95 4.169 0)
			(layer "F.Fab")
			(effects
				(font
					(size 0.7 0.7)
					(thickness 0.15)
				)
				(justify left bottom)
			)
		)
		(fp_text user "License: Apache-2.0"
			(at -0.95 5.169 0)
			(layer "F.Fab")
			(effects
				(font
					(size 0.7 0.7)
					(thickness 0.15)
				)
				(justify left bottom)
			)
		)
		(fp_text user "${REFERENCE}"
			(at -0.95 3.168 0)
			(layer "F.Fab")
			(effects
				(font
					(size 0.7 0.7)
					(thickness 0.15)
				)
				(justify left bottom)
			)
		)
		(pad "1" smd roundrect
			(at -0.48 0)
			(size 0.59 0.64)
			(layers "F.Cu" "F.Mask" "F.Paste")
			(roundrect_rratio 0.25)
			(net 1 "GND")
			(pintype "passive")
		)
		(pad "2" smd roundrect
			(at 0.48 0)
			(size 0.59 0.64)
			(layers "F.Cu" "F.Mask" "F.Paste")
			(roundrect_rratio 0.25)
			(net 804 "Net-(D21-C)")
			(pintype "passive")
		)
	)
	(footprint "antmicro-footprints:WSON-8_6x8x0.5mm_P1.27mm"
		(layer "F.Cu")
		(at 213.8995 152.4995 180)
		(property "Reference" "U27"
			(at -6.9005 -3.0505 0)
			(layer "F.SilkS")
			(effects
				(font
					(size 0.7 0.7)
					(thickness 0.15)
				)
				(justify right bottom)
			)
		)
		(property "Value" "W25Q128JWEIQ"
			(at 0 4.3 0)
			(layer "F.Fab")
			(effects
				(font
					(size 0.7 0.7)
					(thickness 0.15)
				)
				(justify right bottom)
			)
		)
		(property "Datasheet" "https://www.winbond.com/resource-files/W25Q128JW_RevG_07292021%20Plus.pdf"
			(at 0 0 180)
			(layer "F.Fab")
			(hide yes)
			(effects
				(font
					(size 1.27 1.27)
					(thickness 0.15)
				)
			)
		)
		(property "Manufacturer" "Winbond"
			(at 0 0 180)
			(unlocked yes)
			(layer "F.Fab")
			(hide yes)
			(effects
				(font
					(size 1 1)
					(thickness 0.15)
				)
			)
		)
		(property "MPN" "W25Q128JWEIQ TR"
			(at 0 0 180)
			(unlocked yes)
			(layer "F.Fab")
			(hide yes)
			(effects
				(font
					(size 1 1)
					(thickness 0.15)
				)
			)
		)
		(property "Author" "Antmicro"
			(at 0 0 180)
			(unlocked yes)
			(layer "F.Fab")
			(hide yes)
			(effects
				(font
					(size 1 1)
					(thickness 0.15)
				)
			)
		)
		(property "License" "Apache-2.0"
			(at 0 0 180)
			(unlocked yes)
			(layer "F.Fab")
			(hide yes)
			(effects
				(font
					(size 1 1)
					(thickness 0.15)
				)
			)
		)
		(sheetname "/HyperRAM + QSPI Flash/")
		(sheetfile "hyperram-flash.kicad_sch")
		(attr smd)
		(fp_line
			(start 4.0005 3)
			(end -3.9995 3)
			(stroke
				(width 0.15)
				(type solid)
			)
			(layer "F.SilkS")
		)
		(fp_line
			(start 4 -3)
			(end -3.975 -3)
			(stroke
				(width 0.15)
				(type solid)
			)
			(layer "F.SilkS")
		)
		(fp_circle
			(center -4.2 -2.4)
			(end -4.149 -2.4)
			(stroke
				(width 0.15)
				(type solid)
			)
			(fill yes)
			(layer "F.SilkS")
		)
		(fp_rect
			(start -4.7 -3.25)
			(end 4.7 3.25)
			(stroke
				(width 0.05)
				(type solid)
			)
			(fill no)
			(layer "F.CrtYd")
		)
		(fp_line
			(start 3.9995 3.0005)
			(end -3.9995 3.0005)
			(stroke
				(width 0.15)
				(type solid)
			)
			(layer "F.Fab")
		)
		(fp_line
			(start 3.9995 -2.9995)
			(end 3.9995 3.0005)
			(stroke
				(width 0.15)
				(type solid)
			)
			(layer "F.Fab")
		)
		(fp_line
			(start -3.0015 -2.9995)
			(end 3.9995 -2.9995)
			(stroke
				(width 0.15)
				(type solid)
			)
			(layer "F.Fab")
		)
		(fp_line
			(start -3.0015 -2.9995)
			(end -3.9995 -1.9995)
			(stroke
				(width 0.15)
				(type solid)
			)
			(layer "F.Fab")
		)
		(fp_line
			(start -3.9995 3.0005)
			(end -3.9995 -1.9995)
			(stroke
				(width 0.15)
				(type solid)
			)
			(layer "F.Fab")
		)
		(fp_text user "${REFERENCE}"
			(at 0 10.903 180)
			(layer "F.Fab")
			(effects
				(font
					(size 0.7 0.7)
					(thickness 0.15)
				)
				(justify left bottom)
			)
		)
		(fp_text user "License: Apache-2.0"
			(at 0 13.303 180)
			(layer "F.Fab")
			(effects
				(font
					(size 0.7 0.7)
					(thickness 0.15)
				)
				(justify left bottom)
			)
		)
		(fp_text user "Author: Antmicro"
			(at 0 12.104 180)
			(layer "F.Fab")
			(effects
				(font
					(size 0.7 0.7)
					(thickness 0.15)
				)
				(justify left bottom)
			)
		)
		(pad "1" smd roundrect
			(at -3.9995 -1.9045 90)
			(size 0.4 1.3)
			(layers "F.Cu" "F.Mask" "F.Paste")
			(roundrect_rratio 0.25)
			(net 350 "/FPGA Config/FLASH.~{CS}")
			(pinfunction "~{CS}")
			(pintype "input")
		)
		(pad "2" smd roundrect
			(at -3.9995 -0.6355 90)
			(size 0.4 1.3)
			(layers "F.Cu" "F.Mask" "F.Paste")
			(roundrect_rratio 0.25)
			(net 282 "/HyperRAM + QSPI Flash/IO1")
			(pinfunction "DO/IO1")
			(pintype "bidirectional")
		)
		(pad "3" smd roundrect
			(at -3.9995 0.6345 90)
			(size 0.4 1.3)
			(layers "F.Cu" "F.Mask" "F.Paste")
			(roundrect_rratio 0.25)
			(net 280 "/HyperRAM + QSPI Flash/IO2")
			(pinfunction "~{WP}/IO2")
			(pintype "bidirectional")
		)
		(pad "4" smd roundrect
			(at -3.9995 1.9045 90)
			(size 0.4 1.3)
			(layers "F.Cu" "F.Mask" "F.Paste")
			(roundrect_rratio 0.25)
			(net 1 "GND")
			(pinfunction "V_{SS}")
			(pintype "power_in")
		)
		(pad "5" smd roundrect
			(at 3.9995 1.8755 90)
			(size 0.4 1.3)
			(layers "F.Cu" "F.Mask" "F.Paste")
			(roundrect_rratio 0.25)
			(net 281 "/HyperRAM + QSPI Flash/IO0")
			(pinfunction "DI/IO0")
			(pintype "bidirectional")
		)
		(pad "6" smd roundrect
			(at 3.9995 0.6035 90)
			(size 0.4 1.3)
			(layers "F.Cu" "F.Mask" "F.Paste")
			(roundrect_rratio 0.25)
			(net 355 "/FPGA Config/FLASH.SCK")
			(pinfunction "SCK")
			(pintype "input")
		)
		(pad "7" smd roundrect
			(at 3.9995 -0.6655 90)
			(size 0.4 1.3)
			(layers "F.Cu" "F.Mask" "F.Paste")
			(roundrect_rratio 0.25)
			(net 279 "/HyperRAM + QSPI Flash/IO3")
			(pinfunction "~{HOLD}/IO3")
			(pintype "bidirectional")
		)
		(pad "8" smd roundrect
			(at 3.9995 -1.9355 90)
			(size 0.4 1.3)
			(layers "F.Cu" "F.Mask" "F.Paste")
			(roundrect_rratio 0.25)
			(net 797 "+1V8")
			(pinfunction "V_{CC}")
			(pintype "power_in")
		)
		(pad "9" smd roundrect
			(at -0.0005 -0.0005 180)
			(size 4.8 4.65)
			(layers "F.Cu" "F.Mask" "F.Paste")
			(roundrect_rratio 0.05)
			(chamfer_ratio 0.1)
			(chamfer top_left)
			(net 642 "unconnected-(U27-EP-Pad9)")
			(pinfunction "EP")
			(pintype "no_connect")
		)
	)
)
